(kicad_pcb
	(version 20260206)
	(generator "pcbnew")
	(generator_version "10.0")
	(general
		(thickness 1.6)
		(legacy_teardrops no)
	)
	(paper "A4")
	(title_block
		(title "Wiwynn_Tioga_Pass_MB.brd")
		(comment 1 "Tioga Pass / footprints 4432-4439 of 4770")
	)
	(layers
		(0 "F.Cu" signal "TOP")
		(4 "In1.Cu" signal "L2GND")
		(6 "In2.Cu" signal "L3")
		(8 "In3.Cu" signal "L4GND")
		(10 "In4.Cu" signal "L5")
		(12 "In5.Cu" signal "L6GND")
		(14 "In6.Cu" signal "L7VCC")
		(16 "In7.Cu" signal "L8VCC")
		(18 "In8.Cu" signal "L9GND")
		(20 "In9.Cu" signal "L10")
		(22 "In10.Cu" signal "L11GND")
		(24 "In11.Cu" signal "L12")
		(26 "In12.Cu" signal "L13GND")
		(2 "B.Cu" signal "BOTTOM")
		(9 "F.Adhes" user "F.Adhesive")
		(11 "B.Adhes" user "B.Adhesive")
		(13 "F.Paste" user "Package Geometry/Pastemask Top")
		(15 "B.Paste" user "Package Geometry/Pastemask Bottom")
		(5 "F.SilkS" user "Ref Des/Silkscreen Top")
		(7 "B.SilkS" user "Ref Des/Silkscreen Bottom")
		(1 "F.Mask" user "Board Geometry/Soldermask Top")
		(3 "B.Mask" user "Board Geometry/Soldermask Bottom")
		(17 "Dwgs.User" user "User.Drawings")
		(19 "Cmts.User" user "User.Comments")
		(21 "Eco1.User" user "User.Eco1")
		(23 "Eco2.User" user "User.Eco2")
		(25 "Edge.Cuts" user "Board Geometry/Outline")
		(27 "Margin" user)
		(31 "F.CrtYd" user "Package Geometry/Place Bound Top")
		(29 "B.CrtYd" user "Package Geometry/Place Bound Bottom")
		(35 "F.Fab" user "Ref Des/Assembly Top")
		(33 "B.Fab" user "Ref Des/Assembly Bottom")
	)
	(footprint ""
		(layer "B.Cu")
		(at 375.1072 -57.785 180)
		(property "Reference" "R3W10"
			(at 0.8382 -0.67818 180)
			(unlocked yes)
			(layer "B.SilkS")
			(effects
				(font
					(size 0.4064 0.254)
					(thickness 0.1524)
				)
				(justify left mirror)
			)
		)
		(property "Value" ""
			(at 0 0 0)
			(layer "B.Fab")
			(effects
				(font
					(size 1.27 1.27)
				)
				(justify mirror)
			)
		)
		(duplicate_pad_numbers_are_jumpers no)
		(fp_poly
			(pts
				(xy 0.2794 -0.1016) (xy -0.2794 -0.1016) (xy -0.2794 0.9906) (xy 0.2794 0.9906)
			)
			(stroke
				(width 0)
				(type default)
			)
			(fill no)
			(layer "B.CrtYd")
		)
		(fp_line
			(start 0.2794 0.9906)
			(end -0.2794 0.9906)
			(stroke
				(width 0.1)
				(type default)
			)
			(layer "B.Fab")
		)
		(fp_line
			(start 0.2794 -0.1016)
			(end 0.2794 0.9906)
			(stroke
				(width 0.1)
				(type default)
			)
			(layer "B.Fab")
		)
		(fp_line
			(start -0.2794 0.9906)
			(end -0.2794 -0.1016)
			(stroke
				(width 0.1)
				(type default)
			)
			(layer "B.Fab")
		)
		(fp_line
			(start -0.2794 -0.1016)
			(end 0.2794 -0.1016)
			(stroke
				(width 0.1)
				(type default)
			)
			(layer "B.Fab")
		)
		(pad "1" smd rect
			(at 0 0)
			(size 0.508 0.508)
			(layers "B.Cu" "B.Mask" "B.Paste")
			(net "PVCCIO_CPU0")
		)
		(pad "2" smd rect
			(at 0 0.889)
			(size 0.508 0.508)
			(layers "B.Cu" "B.Mask" "B.Paste")
			(net "P0V7_GTL2104_VREF_1")
		)
		(zone
			(layer "B.Cu")
			(hatch none 0.5)
			(connect_pads
				(clearance 0)
			)
			(min_thickness 0.25)
			(keepout
				(tracks not_allowed)
				(vias allowed)
				(pads allowed)
				(copperpour not_allowed)
				(footprints allowed)
			)
			(placement
				(enabled no)
				(sheetname "")
			)
			(fill
				(thermal_gap 0.5)
				(thermal_bridge_width 0.5)
				(island_removal_mode 0)
			)
			(polygon
				(pts
					(xy 374.8532 -58.42) (xy 375.3612 -58.42) (xy 375.3612 -58.039) (xy 374.8532 -58.039)
				)
			)
		)
		(zone
			(layer "B.Cu")
			(hatch none 0.5)
			(connect_pads
				(clearance 0)
			)
			(min_thickness 0.25)
			(keepout
				(tracks allowed)
				(vias not_allowed)
				(pads allowed)
				(copperpour not_allowed)
				(footprints allowed)
			)
			(placement
				(enabled no)
				(sheetname "")
			)
			(fill
				(thermal_gap 0.5)
				(thermal_bridge_width 0.5)
				(island_removal_mode 0)
			)
			(polygon
				(pts
					(xy 374.8532 -58.039) (xy 375.3612 -58.039) (xy 375.3612 -58.42) (xy 374.8532 -58.42)
				)
			)
		)
	)
	(footprint ""
		(layer "B.Cu")
		(at 500.1514 -140.8684)
		(property "Reference" "R6W38"
			(at 0.8382 -0.67818 0)
			(unlocked yes)
			(layer "B.SilkS")
			(effects
				(font
					(size 0.4064 0.254)
					(thickness 0.1524)
				)
				(justify left mirror)
			)
		)
		(property "Value" ""
			(at 0 0 0)
			(layer "B.Fab")
			(effects
				(font
					(size 1.27 1.27)
				)
				(justify mirror)
			)
		)
		(duplicate_pad_numbers_are_jumpers no)
		(fp_poly
			(pts
				(xy 0.2794 -0.1016) (xy -0.2794 -0.1016) (xy -0.2794 0.9906) (xy 0.2794 0.9906)
			)
			(stroke
				(width 0)
				(type default)
			)
			(fill no)
			(layer "B.CrtYd")
		)
		(fp_line
			(start -0.2794 -0.1016)
			(end 0.2794 -0.1016)
			(stroke
				(width 0.1)
				(type default)
			)
			(layer "B.Fab")
		)
		(fp_line
			(start -0.2794 0.9906)
			(end -0.2794 -0.1016)
			(stroke
				(width 0.1)
				(type default)
			)
			(layer "B.Fab")
		)
		(fp_line
			(start 0.2794 -0.1016)
			(end 0.2794 0.9906)
			(stroke
				(width 0.1)
				(type default)
			)
			(layer "B.Fab")
		)
		(fp_line
			(start 0.2794 0.9906)
			(end -0.2794 0.9906)
			(stroke
				(width 0.1)
				(type default)
			)
			(layer "B.Fab")
		)
		(pad "1" smd rect
			(at 0 0 180)
			(size 0.508 0.508)
			(layers "B.Cu" "B.Mask" "B.Paste")
			(net "DEBUG_CARD2_PRSNT")
		)
		(pad "2" smd rect
			(at 0 0.889 180)
			(size 0.508 0.508)
			(layers "B.Cu" "B.Mask" "B.Paste")
			(net "GND")
		)
		(zone
			(layer "B.Cu")
			(hatch none 0.5)
			(connect_pads
				(clearance 0)
			)
			(min_thickness 0.25)
			(keepout
				(tracks allowed)
				(vias not_allowed)
				(pads allowed)
				(copperpour not_allowed)
				(footprints allowed)
			)
			(placement
				(enabled no)
				(sheetname "")
			)
			(fill
				(thermal_gap 0.5)
				(thermal_bridge_width 0.5)
				(island_removal_mode 0)
			)
			(polygon
				(pts
					(xy 500.4054 -140.6144) (xy 499.8974 -140.6144) (xy 499.8974 -140.2334) (xy 500.4054 -140.2334)
				)
			)
		)
		(zone
			(layer "B.Cu")
			(hatch none 0.5)
			(connect_pads
				(clearance 0)
			)
			(min_thickness 0.25)
			(keepout
				(tracks not_allowed)
				(vias allowed)
				(pads allowed)
				(copperpour not_allowed)
				(footprints allowed)
			)
			(placement
				(enabled no)
				(sheetname "")
			)
			(fill
				(thermal_gap 0.5)
				(thermal_bridge_width 0.5)
				(island_removal_mode 0)
			)
			(polygon
				(pts
					(xy 500.4054 -140.2334) (xy 499.8974 -140.2334) (xy 499.8974 -140.6144) (xy 500.4054 -140.6144)
				)
			)
		)
	)
	(footprint ""
		(layer "B.Cu")
		(at 409.23845 -122.216418)
		(property "Reference" "C2M8"
			(at 0 0 0)
			(layer "B.SilkS")
			(hide yes)
			(effects
				(font
					(size 1.27 1.27)
				)
				(justify mirror)
			)
		)
		(property "Value" ""
			(at 0 0 0)
			(layer "B.Fab")
			(effects
				(font
					(size 1.27 1.27)
				)
				(justify mirror)
			)
		)
		(duplicate_pad_numbers_are_jumpers no)
		(fp_poly
			(pts
				(xy -0.3048 -0.1016) (xy -0.3048 0.9906) (xy 0.3048 0.9906) (xy 0.3048 -0.1016)
			)
			(stroke
				(width 0)
				(type default)
			)
			(fill no)
			(layer "B.CrtYd")
		)
		(fp_line
			(start -0.3048 -0.1016)
			(end 0.3048 -0.1016)
			(stroke
				(width 0.1)
				(type default)
			)
			(layer "B.Fab")
		)
		(fp_line
			(start -0.3048 0.9906)
			(end -0.3048 -0.1016)
			(stroke
				(width 0.1)
				(type default)
			)
			(layer "B.Fab")
		)
		(fp_line
			(start 0.3048 -0.1016)
			(end 0.3048 0.9906)
			(stroke
				(width 0.1)
				(type default)
			)
			(layer "B.Fab")
		)
		(fp_line
			(start 0.3048 0.9906)
			(end -0.3048 0.9906)
			(stroke
				(width 0.1)
				(type default)
			)
			(layer "B.Fab")
		)
		(pad "1" smd rect
			(at 0 0 180)
			(size 0.508 0.508)
			(layers "B.Cu" "B.Mask" "B.Paste")
			(net "P1V05_PCH_STBY")
		)
		(pad "2" smd rect
			(at 0 0.889 180)
			(size 0.508 0.508)
			(layers "B.Cu" "B.Mask" "B.Paste")
			(net "GND")
		)
		(zone
			(layer "B.Cu")
			(hatch none 0.5)
			(connect_pads
				(clearance 0)
			)
			(min_thickness 0.25)
			(keepout
				(tracks allowed)
				(vias not_allowed)
				(pads allowed)
				(copperpour not_allowed)
				(footprints allowed)
			)
			(placement
				(enabled no)
				(sheetname "")
			)
			(fill
				(thermal_gap 0.5)
				(thermal_bridge_width 0.5)
				(island_removal_mode 0)
			)
			(polygon
				(pts
					(xy 409.49245 -121.962418) (xy 408.98445 -121.962418) (xy 408.98445 -121.581418) (xy 409.49245 -121.581418)
				)
			)
		)
		(zone
			(layer "B.Cu")
			(hatch none 0.5)
			(connect_pads
				(clearance 0)
			)
			(min_thickness 0.25)
			(keepout
				(tracks not_allowed)
				(vias allowed)
				(pads allowed)
				(copperpour not_allowed)
				(footprints allowed)
			)
			(placement
				(enabled no)
				(sheetname "")
			)
			(fill
				(thermal_gap 0.5)
				(thermal_bridge_width 0.5)
				(island_removal_mode 0)
			)
			(polygon
				(pts
					(xy 409.49245 -121.581418) (xy 408.98445 -121.581418) (xy 408.98445 -121.962418) (xy 409.49245 -121.962418)
				)
			)
		)
	)
	(footprint ""
		(layer "B.Cu")
		(at 470.027 -59.436 -90)
		(property "Reference" "R1W44"
			(at 0.8382 -0.67818 270)
			(unlocked yes)
			(layer "B.SilkS")
			(effects
				(font
					(size 0.4064 0.254)
					(thickness 0.1524)
				)
				(justify left mirror)
			)
		)
		(property "Value" ""
			(at 0 0 90)
			(layer "B.Fab")
			(effects
				(font
					(size 1.27 1.27)
				)
				(justify mirror)
			)
		)
		(duplicate_pad_numbers_are_jumpers no)
		(fp_poly
			(pts
				(xy 0.2794 -0.1016) (xy -0.2794 -0.1016) (xy -0.2794 0.9906) (xy 0.2794 0.9906)
			)
			(stroke
				(width 0)
				(type default)
			)
			(fill no)
			(layer "B.CrtYd")
		)
		(fp_line
			(start -0.2794 0.9906)
			(end -0.2794 -0.1016)
			(stroke
				(width 0.1)
				(type default)
			)
			(layer "B.Fab")
		)
		(fp_line
			(start 0.2794 0.9906)
			(end -0.2794 0.9906)
			(stroke
				(width 0.1)
				(type default)
			)
			(layer "B.Fab")
		)
		(fp_line
			(start -0.2794 -0.1016)
			(end 0.2794 -0.1016)
			(stroke
				(width 0.1)
				(type default)
			)
			(layer "B.Fab")
		)
		(fp_line
			(start 0.2794 -0.1016)
			(end 0.2794 0.9906)
			(stroke
				(width 0.1)
				(type default)
			)
			(layer "B.Fab")
		)
		(pad "1" smd rect
			(at 0 0 90)
			(size 0.508 0.508)
			(layers "B.Cu" "B.Mask" "B.Paste")
			(net "P3V3_STBY")
		)
		(pad "2" smd rect
			(at 0 0.889 90)
			(size 0.508 0.508)
			(layers "B.Cu" "B.Mask" "B.Paste")
			(net "FM_GBE2_LVC3_MOD_ABS")
		)
		(zone
			(layer "B.Cu")
			(hatch none 0.5)
			(connect_pads
				(clearance 0)
			)
			(min_thickness 0.25)
			(keepout
				(tracks not_allowed)
				(vias allowed)
				(pads allowed)
				(copperpour not_allowed)
				(footprints allowed)
			)
			(placement
				(enabled no)
				(sheetname "")
			)
			(fill
				(thermal_gap 0.5)
				(thermal_bridge_width 0.5)
				(island_removal_mode 0)
			)
			(polygon
				(pts
					(xy 469.392 -59.182) (xy 469.392 -59.69) (xy 469.773 -59.69) (xy 469.773 -59.182)
				)
			)
		)
		(zone
			(layer "B.Cu")
			(hatch none 0.5)
			(connect_pads
				(clearance 0)
			)
			(min_thickness 0.25)
			(keepout
				(tracks allowed)
				(vias not_allowed)
				(pads allowed)
				(copperpour not_allowed)
				(footprints allowed)
			)
			(placement
				(enabled no)
				(sheetname "")
			)
			(fill
				(thermal_gap 0.5)
				(thermal_bridge_width 0.5)
				(island_removal_mode 0)
			)
			(polygon
				(pts
					(xy 469.773 -59.182) (xy 469.773 -59.69) (xy 469.392 -59.69) (xy 469.392 -59.182)
				)
			)
		)
	)
	(footprint ""
		(layer "B.Cu")
		(at 120.65 -31.115)
		(property "Reference" ""
			(at 0 0 0)
			(layer "B.SilkS")
			(hide yes)
			(effects
				(font
					(size 1.27 1.27)
				)
				(justify mirror)
			)
		)
		(property "Value" ""
			(at 0 0 0)
			(layer "B.Fab")
			(effects
				(font
					(size 1.27 1.27)
				)
				(justify mirror)
			)
		)
		(duplicate_pad_numbers_are_jumpers no)
		(fp_poly
			(pts
				(arc
					(start 2.032 0)
					(mid -2.032 0)
					(end 2.032 0)
				)
			)
			(stroke
				(width 0)
				(type default)
			)
			(fill no)
			(layer "B.CrtYd")
		)
		(pad "1" smd circle
			(at 0 0 180)
			(size 1.016 1.016)
			(layers "B.Cu" "B.Mask" "B.Paste")
			(net "Net_388")
		)
		(zone
			(layers "F.Cu" "B.Cu" "In1.Cu" "In2.Cu" "In3.Cu" "In4.Cu" "In5.Cu" "In6.Cu"
				"In7.Cu" "In8.Cu" "In9.Cu" "In10.Cu" "In11.Cu" "In12.Cu"
			)
			(hatch none 0.5)
			(connect_pads
				(clearance 0)
			)
			(min_thickness 0.25)
			(keepout
				(tracks allowed)
				(vias not_allowed)
				(pads allowed)
				(copperpour not_allowed)
				(footprints allowed)
			)
			(placement
				(enabled no)
				(sheetname "")
			)
			(fill
				(thermal_gap 0.5)
				(thermal_bridge_width 0.5)
				(island_removal_mode 0)
			)
			(polygon
				(pts
					(arc
						(start 122.174 -31.115)
						(mid 119.126 -31.115)
						(end 122.174 -31.115)
					)
				)
			)
		)
		(zone
			(layer "B.Cu")
			(hatch none 0.5)
			(connect_pads
				(clearance 0)
			)
			(min_thickness 0.25)
			(keepout
				(tracks not_allowed)
				(vias allowed)
				(pads allowed)
				(copperpour not_allowed)
				(footprints allowed)
			)
			(placement
				(enabled no)
				(sheetname "")
			)
			(fill
				(thermal_gap 0.5)
				(thermal_bridge_width 0.5)
				(island_removal_mode 0)
			)
			(polygon
				(pts
					(arc
						(start 122.174 -31.115)
						(mid 119.126 -31.115)
						(end 122.174 -31.115)
					)
				)
			)
		)
	)
	(footprint ""
		(layer "B.Cu")
		(at 227.584 -90.297 90)
		(property "Reference" "R5N5"
			(at 0 0 90)
			(layer "B.SilkS")
			(hide yes)
			(effects
				(font
					(size 1.27 1.27)
				)
				(justify mirror)
			)
		)
		(property "Value" ""
			(at 0 0 90)
			(layer "B.Fab")
			(effects
				(font
					(size 1.27 1.27)
				)
				(justify mirror)
			)
		)
		(duplicate_pad_numbers_are_jumpers no)
		(fp_poly
			(pts
				(xy 0.2794 -0.1016) (xy -0.2794 -0.1016) (xy -0.2794 0.9906) (xy 0.2794 0.9906)
			)
			(stroke
				(width 0)
				(type default)
			)
			(fill no)
			(layer "B.CrtYd")
		)
		(fp_line
			(start 0.2794 -0.1016)
			(end 0.2794 0.9906)
			(stroke
				(width 0.1)
				(type default)
			)
			(layer "B.Fab")
		)
		(fp_line
			(start -0.2794 -0.1016)
			(end 0.2794 -0.1016)
			(stroke
				(width 0.1)
				(type default)
			)
			(layer "B.Fab")
		)
		(fp_line
			(start 0.2794 0.9906)
			(end -0.2794 0.9906)
			(stroke
				(width 0.1)
				(type default)
			)
			(layer "B.Fab")
		)
		(fp_line
			(start -0.2794 0.9906)
			(end -0.2794 -0.1016)
			(stroke
				(width 0.1)
				(type default)
			)
			(layer "B.Fab")
		)
		(pad "1" smd rect
			(at 0 0 270)
			(size 0.508 0.508)
			(layers "B.Cu" "B.Mask" "B.Paste")
			(net "P3V3_STBY")
		)
		(pad "2" smd rect
			(at 0 0.889 270)
			(size 0.508 0.508)
			(layers "B.Cu" "B.Mask" "B.Paste")
			(net "FM_CPU0_PKGID1")
		)
		(zone
			(layer "B.Cu")
			(hatch none 0.5)
			(connect_pads
				(clearance 0)
			)
			(min_thickness 0.25)
			(keepout
				(tracks allowed)
				(vias not_allowed)
				(pads allowed)
				(copperpour not_allowed)
				(footprints allowed)
			)
			(placement
				(enabled no)
				(sheetname "")
			)
			(fill
				(thermal_gap 0.5)
				(thermal_bridge_width 0.5)
				(island_removal_mode 0)
			)
			(polygon
				(pts
					(xy 227.838 -90.551) (xy 227.838 -90.043) (xy 228.219 -90.043) (xy 228.219 -90.551)
				)
			)
		)
		(zone
			(layer "B.Cu")
			(hatch none 0.5)
			(connect_pads
				(clearance 0)
			)
			(min_thickness 0.25)
			(keepout
				(tracks not_allowed)
				(vias allowed)
				(pads allowed)
				(copperpour not_allowed)
				(footprints allowed)
			)
			(placement
				(enabled no)
				(sheetname "")
			)
			(fill
				(thermal_gap 0.5)
				(thermal_bridge_width 0.5)
				(island_removal_mode 0)
			)
			(polygon
				(pts
					(xy 228.219 -90.551) (xy 228.219 -90.043) (xy 227.838 -90.043) (xy 227.838 -90.551)
				)
			)
		)
	)
	(footprint ""
		(layer "B.Cu")
		(at 256.853436 -157.016958 90)
		(property "Reference" "C5L4"
			(at -1.47828 0.78994 180)
			(unlocked yes)
			(layer "B.SilkS")
			(effects
				(font
					(size 0.4064 0.254)
					(thickness 0.1524)
				)
				(justify mirror)
			)
		)
		(property "Value" ""
			(at 0 0 90)
			(layer "B.Fab")
			(effects
				(font
					(size 1.27 1.27)
				)
				(justify mirror)
			)
		)
		(duplicate_pad_numbers_are_jumpers no)
		(fp_poly
			(pts
				(xy 0.7239 -0.2159) (xy -0.7239 -0.2159) (xy -0.7239 1.9939) (xy 0.7239 1.9939)
			)
			(stroke
				(width 0)
				(type default)
			)
			(fill no)
			(layer "B.CrtYd")
		)
		(fp_line
			(start 0.7239 -0.2159)
			(end 0.7239 1.9939)
			(stroke
				(width 0.1)
				(type default)
			)
			(layer "B.Fab")
		)
		(fp_line
			(start -0.7239 -0.2159)
			(end 0.7239 -0.2159)
			(stroke
				(width 0.1)
				(type default)
			)
			(layer "B.Fab")
		)
		(fp_line
			(start 0.7239 1.9939)
			(end -0.7239 1.9939)
			(stroke
				(width 0.1)
				(type default)
			)
			(layer "B.Fab")
		)
		(fp_line
			(start -0.7239 1.9939)
			(end -0.7239 -0.2159)
			(stroke
				(width 0.1)
				(type default)
			)
			(layer "B.Fab")
		)
		(pad "1" smd rect
			(at 0 0 270)
			(size 1.27 1.016)
			(layers "B.Cu" "B.Mask" "B.Paste")
			(net "PVTT_DEF")
		)
		(pad "2" smd rect
			(at 0 1.778 270)
			(size 1.27 1.016)
			(layers "B.Cu" "B.Mask" "B.Paste")
			(net "GND")
		)
		(zone
			(layer "B.Cu")
			(hatch none 0.5)
			(connect_pads
				(clearance 0)
			)
			(min_thickness 0.25)
			(keepout
				(tracks not_allowed)
				(vias allowed)
				(pads allowed)
				(copperpour not_allowed)
				(footprints allowed)
			)
			(placement
				(enabled no)
				(sheetname "")
			)
			(fill
				(thermal_gap 0.5)
				(thermal_bridge_width 0.5)
				(island_removal_mode 0)
			)
			(polygon
				(pts
					(xy 257.361436 -157.651958) (xy 257.361436 -156.381958) (xy 258.123436 -156.381958) (xy 258.123436 -157.651958)
				)
			)
		)
	)
	(footprint ""
		(layer "B.Cu")
		(at 361.782614 -125.558042 -90)
		(property "Reference" "R781"
			(at 0.8382 -0.67818 270)
			(unlocked yes)
			(layer "B.SilkS")
			(effects
				(font
					(size 0.4064 0.254)
					(thickness 0.1524)
				)
				(justify left mirror)
			)
		)
		(property "Value" ""
			(at 0 0 90)
			(layer "B.Fab")
			(effects
				(font
					(size 1.27 1.27)
				)
				(justify mirror)
			)
		)
		(duplicate_pad_numbers_are_jumpers no)
		(fp_poly
			(pts
				(xy 0.2794 -0.1016) (xy -0.2794 -0.1016) (xy -0.2794 0.9906) (xy 0.2794 0.9906)
			)
			(stroke
				(width 0)
				(type default)
			)
			(fill no)
			(layer "B.CrtYd")
		)
		(fp_line
			(start -0.2794 0.9906)
			(end -0.2794 -0.1016)
			(stroke
				(width 0.1)
				(type default)
			)
			(layer "B.Fab")
		)
		(fp_line
			(start 0.2794 0.9906)
			(end -0.2794 0.9906)
			(stroke
				(width 0.1)
				(type default)
			)
			(layer "B.Fab")
		)
		(fp_line
			(start -0.2794 -0.1016)
			(end 0.2794 -0.1016)
			(stroke
				(width 0.1)
				(type default)
			)
			(layer "B.Fab")
		)
		(fp_line
			(start 0.2794 -0.1016)
			(end 0.2794 0.9906)
			(stroke
				(width 0.1)
				(type default)
			)
			(layer "B.Fab")
		)
		(pad "1" smd rect
			(at 0 0 90)
			(size 0.508 0.508)
			(layers "B.Cu" "B.Mask" "B.Paste")
			(net "P3E_CPU0_PE1_PCH_RXP<10>")
		)
		(pad "2" smd rect
			(at 0 0.889 90)
			(size 0.508 0.508)
			(layers "B.Cu" "B.Mask" "B.Paste")
			(net "P3E_CPU0_PE1_PCH_CON_RXP<10>")
		)
		(zone
			(layer "B.Cu")
			(hatch none 0.5)
			(connect_pads
				(clearance 0)
			)
			(min_thickness 0.25)
			(keepout
				(tracks not_allowed)
				(vias allowed)
				(pads allowed)
				(copperpour not_allowed)
				(footprints allowed)
			)
			(placement
				(enabled no)
				(sheetname "")
			)
			(fill
				(thermal_gap 0.5)
				(thermal_bridge_width 0.5)
				(island_removal_mode 0)
			)
			(polygon
				(pts
					(xy 361.147614 -125.304042) (xy 361.147614 -125.812042) (xy 361.528614 -125.812042) (xy 361.528614 -125.304042)
				)
			)
		)
		(zone
			(layer "B.Cu")
			(hatch none 0.5)
			(connect_pads
				(clearance 0)
			)
			(min_thickness 0.25)
			(keepout
				(tracks allowed)
				(vias not_allowed)
				(pads allowed)
				(copperpour not_allowed)
				(footprints allowed)
			)
			(placement
				(enabled no)
				(sheetname "")
			)
			(fill
				(thermal_gap 0.5)
				(thermal_bridge_width 0.5)
				(island_removal_mode 0)
			)
			(polygon
				(pts
					(xy 361.528614 -125.304042) (xy 361.528614 -125.812042) (xy 361.147614 -125.812042) (xy 361.147614 -125.304042)
				)
			)
		)
	)
)
